FILE_TYPE=LIBRARY_PARTS;
primitive 'DUMMY_SYMBOL';
  pin
    '1':
      PIN_NUMBER='(1)';
      OUTPUT_TYPE='(TS,TS)';
      INPUT_LOAD='(-0.01,0.01)';
      OUTPUT_LOAD='(1.0,-1.0)';
  end_pin;
  body
    PART_NAME='DUMMY_SYMBOL';
    BODY_NAME='DUMMY_SYMBOL';
    PHYS_DES_PREFIX='DM';
    CLASS='DISCRETE';
  end_body;
end_primitive;

END.
